# SCM (Grand Teton) — schematic netlist excerpt (pin names and nets, part order shuffled) for the footprints in the layout excerpt that follows; sources: Cadence DE-HDL packaged netlist, KiCad conversion of 12092022_DA0F0TMDCD0_F0T_Management_Board_D_brd_V3_OCP.brd

R503  Q_RES  0 5% CHIP  pkg 0402LF  page 46 : A = RST_PLTRST_TPM_N ; B = RST_PLTRST_N
C228  Q_CAP  0.1UF 25V 10% EMPTY  pkg 0402  page 21 : A = P3V3_AUX ; B = GND

(kicad_pcb
	(version 20260206)
	(generator "pcbnew")
	(generator_version "10.0")
	(general
		(thickness 1.6)
		(legacy_teardrops no)
	)
	(paper "A4")
	(title_block
		(title "12092022_DA0F0TMDCD0_F0T_Management_Board_D_brd_V3_OCP.brd")
		(comment 1 "Grand Teton / footprints 268-269 of 1440")
	)
	(layers
		(0 "F.Cu" signal "TOP")
		(4 "In1.Cu" signal "GND")
		(6 "In2.Cu" signal "IN1")
		(8 "In3.Cu" signal "GND1")
		(10 "In4.Cu" signal "IN2")
		(12 "In5.Cu" signal "VCC")
		(14 "In6.Cu" signal "VCC1")
		(16 "In7.Cu" signal "IN3")
		(18 "In8.Cu" signal "GND2")
		(20 "In9.Cu" signal "IN4")
		(22 "In10.Cu" signal "GND3")
		(2 "B.Cu" signal "BOTTOM")
		(9 "F.Adhes" user "F.Adhesive")
		(11 "B.Adhes" user "B.Adhesive")
		(13 "F.Paste" user "Package Geometry/Pastemask Top")
		(15 "B.Paste" user "Package Geometry/Pastemask Bottom")
		(5 "F.SilkS" user "Ref Des/Silkscreen Top")
		(7 "B.SilkS" user "Ref Des/Silkscreen Bottom")
		(1 "F.Mask" user "Board Geometry/Soldermask Top")
		(3 "B.Mask" user "Board Geometry/Soldermask Bottom")
		(17 "Dwgs.User" user "User.Drawings")
		(19 "Cmts.User" user "User.Comments")
		(21 "Eco1.User" user "User.Eco1")
		(23 "Eco2.User" user "User.Eco2")
		(25 "Edge.Cuts" user "Board Geometry/Outline")
		(27 "Margin" user)
		(31 "F.CrtYd" user "Package Geometry/Place Bound Top")
		(29 "B.CrtYd" user "Package Geometry/Place Bound Bottom")
		(35 "F.Fab" user "Ref Des/Assembly Top")
		(33 "B.Fab" user "Ref Des/Assembly Bottom")
	)
	(footprint ""
		(layer "F.Cu")
		(at 68.189094 -92.61094)
		(property "Reference" "R503"
			(at 0 0 0)
			(layer "F.SilkS")
			(hide yes)
			(effects
				(font
					(size 1.27 1.27)
				)
			)
		)
		(property "Value" ""
			(at 0 0 0)
			(layer "F.Fab")
			(effects
				(font
					(size 1.27 1.27)
				)
			)
		)
		(duplicate_pad_numbers_are_jumpers no)
		(fp_line
			(start -0.7874 -0.4064)
			(end 0.7874 -0.4064)
			(stroke
				(width 0.1524)
				(type default)
			)
			(layer "F.SilkS")
		)
		(fp_line
			(start -0.7874 0.4064)
			(end -0.7874 -0.4064)
			(stroke
				(width 0.1524)
				(type default)
			)
			(layer "F.SilkS")
		)
		(fp_line
			(start 0.7874 -0.4064)
			(end 0.7874 0.4064)
			(stroke
				(width 0.1524)
				(type default)
			)
			(layer "F.SilkS")
		)
		(fp_line
			(start 0.7874 0.4064)
			(end -0.7874 0.4064)
			(stroke
				(width 0.1524)
				(type default)
			)
			(layer "F.SilkS")
		)
		(fp_line
			(start -0.67945 -0.305054)
			(end -0.12065 -0.305054)
			(stroke
				(width 0.1)
				(type default)
			)
			(layer "F.Fab")
		)
		(fp_line
			(start -0.67945 0.3048)
			(end -0.67945 -0.305054)
			(stroke
				(width 0.1)
				(type default)
			)
			(layer "F.Fab")
		)
		(fp_line
			(start -0.12065 -0.305054)
			(end -0.12065 -0.2794)
			(stroke
				(width 0.1)
				(type default)
			)
			(layer "F.Fab")
		)
		(fp_line
			(start -0.12065 -0.2794)
			(end 0.12065 -0.2794)
			(stroke
				(width 0.1)
				(type default)
			)
			(layer "F.Fab")
		)
		(fp_line
			(start -0.12065 0.2794)
			(end -0.12065 0.3048)
			(stroke
				(width 0.1)
				(type default)
			)
			(layer "F.Fab")
		)
		(fp_line
			(start -0.12065 0.3048)
			(end -0.67945 0.3048)
			(stroke
				(width 0.1)
				(type default)
			)
			(layer "F.Fab")
		)
		(fp_line
			(start 0.120396 0.2794)
			(end -0.12065 0.2794)
			(stroke
				(width 0.1)
				(type default)
			)
			(layer "F.Fab")
		)
		(fp_line
			(start 0.120396 0.3048)
			(end 0.120396 0.2794)
			(stroke
				(width 0.1)
				(type default)
			)
			(layer "F.Fab")
		)
		(fp_line
			(start 0.12065 -0.3048)
			(end 0.67945 -0.3048)
			(stroke
				(width 0.1)
				(type default)
			)
			(layer "F.Fab")
		)
		(fp_line
			(start 0.12065 -0.2794)
			(end 0.12065 -0.3048)
			(stroke
				(width 0.1)
				(type default)
			)
			(layer "F.Fab")
		)
		(fp_line
			(start 0.67945 -0.3048)
			(end 0.67945 0.3048)
			(stroke
				(width 0.1)
				(type default)
			)
			(layer "F.Fab")
		)
		(fp_line
			(start 0.67945 0.3048)
			(end 0.120396 0.3048)
			(stroke
				(width 0.1)
				(type default)
			)
			(layer "F.Fab")
		)
		(pad "1" smd circle
			(at -0.40005 0)
			(size 0 0)
			(layers "F.Cu" "F.Mask" "F.Paste")
			(net "RST_PLTRST_TPM_N")
		)
		(pad "2" smd circle
			(at 0.40005 0)
			(size 0 0)
			(layers "F.Cu" "F.Mask" "F.Paste")
			(net "RST_PLTRST_N")
		)
	)
	(footprint ""
		(layer "F.Cu")
		(at 36.1442 -70.4088 -90)
		(property "Reference" "C228"
			(at 0 0 270)
			(layer "F.SilkS")
			(hide yes)
			(effects
				(font
					(size 1.27 1.27)
				)
			)
		)
		(property "Value" ""
			(at 0 0 270)
			(layer "F.Fab")
			(effects
				(font
					(size 1.27 1.27)
				)
			)
		)
		(duplicate_pad_numbers_are_jumpers no)
		(fp_line
			(start -0.7874 0.4064)
			(end -0.7874 -0.4064)
			(stroke
				(width 0.1524)
				(type default)
			)
			(layer "F.SilkS")
		)
		(fp_line
			(start 0.7874 0.4064)
			(end -0.7874 0.4064)
			(stroke
				(width 0.1524)
				(type default)
			)
			(layer "F.SilkS")
		)
		(fp_line
			(start -0.7874 -0.4064)
			(end 0.7874 -0.4064)
			(stroke
				(width 0.1524)
				(type default)
			)
			(layer "F.SilkS")
		)
		(fp_line
			(start 0.7874 -0.4064)
			(end 0.7874 0.4064)
			(stroke
				(width 0.1524)
				(type default)
			)
			(layer "F.SilkS")
		)
		(fp_line
			(start -0.67945 0.3048)
			(end -0.67945 -0.305054)
			(stroke
				(width 0.1)
				(type default)
			)
			(layer "F.Fab")
		)
		(fp_line
			(start -0.12065 0.3048)
			(end -0.67945 0.3048)
			(stroke
				(width 0.1)
				(type default)
			)
			(layer "F.Fab")
		)
		(fp_line
			(start 0.120396 0.3048)
			(end 0.120396 0.2794)
			(stroke
				(width 0.1)
				(type default)
			)
			(layer "F.Fab")
		)
		(fp_line
			(start 0.67945 0.3048)
			(end 0.120396 0.3048)
			(stroke
				(width 0.1)
				(type default)
			)
			(layer "F.Fab")
		)
		(fp_line
			(start -0.12065 0.2794)
			(end -0.12065 0.3048)
			(stroke
				(width 0.1)
				(type default)
			)
			(layer "F.Fab")
		)
		(fp_line
			(start 0.120396 0.2794)
			(end -0.12065 0.2794)
			(stroke
				(width 0.1)
				(type default)
			)
			(layer "F.Fab")
		)
		(fp_line
			(start -0.12065 -0.2794)
			(end 0.12065 -0.2794)
			(stroke
				(width 0.1)
				(type default)
			)
			(layer "F.Fab")
		)
		(fp_line
			(start 0.12065 -0.2794)
			(end 0.12065 -0.3048)
			(stroke
				(width 0.1)
				(type default)
			)
			(layer "F.Fab")
		)
		(fp_line
			(start 0.12065 -0.3048)
			(end 0.67945 -0.3048)
			(stroke
				(width 0.1)
				(type default)
			)
			(layer "F.Fab")
		)
		(fp_line
			(start 0.67945 -0.3048)
			(end 0.67945 0.3048)
			(stroke
				(width 0.1)
				(type default)
			)
			(layer "F.Fab")
		)
		(fp_line
			(start -0.67945 -0.305054)
			(end -0.12065 -0.305054)
			(stroke
				(width 0.1)
				(type default)
			)
			(layer "F.Fab")
		)
		(fp_line
			(start -0.12065 -0.305054)
			(end -0.12065 -0.2794)
			(stroke
				(width 0.1)
				(type default)
			)
			(layer "F.Fab")
		)
		(pad "1" smd circle
			(at -0.40005 0 270)
			(size 0 0)
			(layers "F.Cu" "F.Mask" "F.Paste")
			(net "P3V3_AUX")
		)
		(pad "2" smd circle
			(at 0.40005 0 270)
			(size 0 0)
			(layers "F.Cu" "F.Mask" "F.Paste")
			(net "GND")
		)
	)
)
